# BASEBOARD_FAB2 (Tioga Pass) — schematic netlist excerpt (pin names and nets, part order shuffled) for the footprints in the layout excerpt that follows; sources: Cadence DE-HDL packaged netlist, KiCad conversion of Wiwynn_Tioga_Pass_MB.brd

CF18  SC22P50V2JN-4GP  5%  pkg SMD-BCG  page 218 : \1\ = VR_PVDDQ_DEF_AIREF2 ; \2\ = ISENSE_PVDDQ_DEF_PH2_IMON
C2T25  CAP_A  0.1UF 16V 10% X7R  pkg 0402V  page 101 : A = P3V3_STBY_MNG ; B = GND
C5G62  CAP_A  22.0UF 4V 20% X6S  pkg 0603V  page 242 : A = PVDDQ_DEF ; B = GND

(kicad_pcb
	(version 20260206)
	(generator "pcbnew")
	(generator_version "10.0")
	(general
		(thickness 1.6)
		(legacy_teardrops no)
	)
	(paper "A4")
	(title_block
		(title "Wiwynn_Tioga_Pass_MB.brd")
		(comment 1 "Tioga Pass / footprints 4111-4113 of 4770")
	)
	(layers
		(0 "F.Cu" signal "TOP")
		(4 "In1.Cu" signal "L2GND")
		(6 "In2.Cu" signal "L3")
		(8 "In3.Cu" signal "L4GND")
		(10 "In4.Cu" signal "L5")
		(12 "In5.Cu" signal "L6GND")
		(14 "In6.Cu" signal "L7VCC")
		(16 "In7.Cu" signal "L8VCC")
		(18 "In8.Cu" signal "L9GND")
		(20 "In9.Cu" signal "L10")
		(22 "In10.Cu" signal "L11GND")
		(24 "In11.Cu" signal "L12")
		(26 "In12.Cu" signal "L13GND")
		(2 "B.Cu" signal "BOTTOM")
		(9 "F.Adhes" user "F.Adhesive")
		(11 "B.Adhes" user "B.Adhesive")
		(13 "F.Paste" user "Package Geometry/Pastemask Top")
		(15 "B.Paste" user "Package Geometry/Pastemask Bottom")
		(5 "F.SilkS" user "Ref Des/Silkscreen Top")
		(7 "B.SilkS" user "Ref Des/Silkscreen Bottom")
		(1 "F.Mask" user "Board Geometry/Soldermask Top")
		(3 "B.Mask" user "Board Geometry/Soldermask Bottom")
		(17 "Dwgs.User" user "User.Drawings")
		(19 "Cmts.User" user "User.Comments")
		(21 "Eco1.User" user "User.Eco1")
		(23 "Eco2.User" user "User.Eco2")
		(25 "Edge.Cuts" user "Board Geometry/Outline")
		(27 "Margin" user)
		(31 "F.CrtYd" user "Package Geometry/Place Bound Top")
		(29 "B.CrtYd" user "Package Geometry/Place Bound Bottom")
		(35 "F.Fab" user "Ref Des/Assembly Top")
		(33 "B.Fab" user "Ref Des/Assembly Bottom")
	)
	(footprint ""
		(layer "B.Cu")
		(at 481.27666 -29.35732 -90)
		(property "Reference" "C2T25"
			(at 0 0 90)
			(layer "B.SilkS")
			(hide yes)
			(effects
				(font
					(size 1.27 1.27)
				)
				(justify mirror)
			)
		)
		(property "Value" ""
			(at 0 0 90)
			(layer "B.Fab")
			(effects
				(font
					(size 1.27 1.27)
				)
				(justify mirror)
			)
		)
		(duplicate_pad_numbers_are_jumpers no)
		(fp_poly
			(pts
				(xy -0.3048 -0.1016) (xy -0.3048 0.9906) (xy 0.3048 0.9906) (xy 0.3048 -0.1016)
			)
			(stroke
				(width 0)
				(type default)
			)
			(fill no)
			(layer "B.CrtYd")
		)
		(fp_line
			(start -0.3048 0.9906)
			(end -0.3048 -0.1016)
			(stroke
				(width 0.1)
				(type default)
			)
			(layer "B.Fab")
		)
		(fp_line
			(start 0.3048 0.9906)
			(end -0.3048 0.9906)
			(stroke
				(width 0.1)
				(type default)
			)
			(layer "B.Fab")
		)
		(fp_line
			(start -0.3048 -0.1016)
			(end 0.3048 -0.1016)
			(stroke
				(width 0.1)
				(type default)
			)
			(layer "B.Fab")
		)
		(fp_line
			(start 0.3048 -0.1016)
			(end 0.3048 0.9906)
			(stroke
				(width 0.1)
				(type default)
			)
			(layer "B.Fab")
		)
		(pad "1" smd rect
			(at 0 0 90)
			(size 0.508 0.508)
			(layers "B.Cu" "B.Mask" "B.Paste")
			(net "P3V3_STBY_MNG")
		)
		(pad "2" smd rect
			(at 0 0.889 90)
			(size 0.508 0.508)
			(layers "B.Cu" "B.Mask" "B.Paste")
			(net "GND")
		)
		(zone
			(layer "B.Cu")
			(hatch none 0.5)
			(connect_pads
				(clearance 0)
			)
			(min_thickness 0.25)
			(keepout
				(tracks not_allowed)
				(vias allowed)
				(pads allowed)
				(copperpour not_allowed)
				(footprints allowed)
			)
			(placement
				(enabled no)
				(sheetname "")
			)
			(fill
				(thermal_gap 0.5)
				(thermal_bridge_width 0.5)
				(island_removal_mode 0)
			)
			(polygon
				(pts
					(xy 480.64166 -29.10332) (xy 480.64166 -29.61132) (xy 481.02266 -29.61132) (xy 481.02266 -29.10332)
				)
			)
		)
		(zone
			(layer "B.Cu")
			(hatch none 0.5)
			(connect_pads
				(clearance 0)
			)
			(min_thickness 0.25)
			(keepout
				(tracks allowed)
				(vias not_allowed)
				(pads allowed)
				(copperpour not_allowed)
				(footprints allowed)
			)
			(placement
				(enabled no)
				(sheetname "")
			)
			(fill
				(thermal_gap 0.5)
				(thermal_bridge_width 0.5)
				(island_removal_mode 0)
			)
			(polygon
				(pts
					(xy 481.02266 -29.10332) (xy 481.02266 -29.61132) (xy 480.64166 -29.61132) (xy 480.64166 -29.10332)
				)
			)
		)
	)
	(footprint ""
		(layer "B.Cu")
		(at 253.392432 -149.8092 90)
		(property "Reference" "C5G62"
			(at -1.14681 0.76708 180)
			(unlocked yes)
			(layer "B.SilkS")
			(effects
				(font
					(size 0.7874 0.5842)
					(thickness 0.1524)
				)
				(justify mirror)
			)
		)
		(property "Value" ""
			(at 0 0 90)
			(layer "B.Fab")
			(effects
				(font
					(size 1.27 1.27)
				)
				(justify mirror)
			)
		)
		(duplicate_pad_numbers_are_jumpers no)
		(fp_rect
			(start -0.4953 -0.2032)
			(end 0.4953 1.6002)
			(stroke
				(width 0)
				(type default)
			)
			(fill no)
			(layer "B.CrtYd")
		)
		(fp_line
			(start 0.4953 -0.2032)
			(end -0.4953 -0.2032)
			(stroke
				(width 0.1)
				(type default)
			)
			(layer "B.Fab")
		)
		(fp_line
			(start -0.4953 -0.2032)
			(end -0.4953 1.6002)
			(stroke
				(width 0.1)
				(type default)
			)
			(layer "B.Fab")
		)
		(fp_line
			(start 0.4953 1.6002)
			(end 0.4953 -0.2032)
			(stroke
				(width 0.1)
				(type default)
			)
			(layer "B.Fab")
		)
		(fp_line
			(start -0.4953 1.6002)
			(end 0.4953 1.6002)
			(stroke
				(width 0.1)
				(type default)
			)
			(layer "B.Fab")
		)
		(pad "1" smd rect
			(at 0 0 270)
			(size 0.762 0.889)
			(layers "B.Cu" "B.Mask" "B.Paste")
			(net "PVDDQ_DEF")
		)
		(pad "2" smd rect
			(at 0 1.397 270)
			(size 0.762 0.889)
			(layers "B.Cu" "B.Mask" "B.Paste")
			(net "GND")
		)
		(zone
			(layer "B.Cu")
			(hatch none 0.5)
			(connect_pads
				(clearance 0)
			)
			(min_thickness 0.25)
			(keepout
				(tracks not_allowed)
				(vias allowed)
				(pads allowed)
				(copperpour not_allowed)
				(footprints allowed)
			)
			(placement
				(enabled no)
				(sheetname "")
			)
			(fill
				(thermal_gap 0.5)
				(thermal_bridge_width 0.5)
				(island_removal_mode 0)
			)
			(polygon
				(pts
					(xy 253.836932 -149.4282) (xy 254.344932 -149.4282) (xy 254.344932 -150.1902) (xy 253.836932 -150.1902)
				)
			)
		)
	)
	(footprint ""
		(layer "B.Cu")
		(at 360.2228 -141.833092 -90)
		(property "Reference" "CF18"
			(at 0 0 90)
			(layer "B.SilkS")
			(hide yes)
			(effects
				(font
					(size 1.27 1.27)
				)
				(justify mirror)
			)
		)
		(property "Value" "*"
			(at -1.1811 -2.8194 270)
			(unlocked yes)
			(layer "B.Fab")
			(hide yes)
			(effects
				(font
					(size 1.27 1.016)
					(thickness 0.1524)
				)
				(justify mirror)
			)
		)
		(property "Device Type" "SC22P50V2JN-4GP_SMD-BCG-SC22P5A"
			(at -1.1811 -4.3434 270)
			(unlocked yes)
			(layer "B.Fab")
			(hide yes)
			(effects
				(font
					(size 1.27 1.016)
					(thickness 0.1524)
				)
				(justify mirror)
			)
		)
		(duplicate_pad_numbers_are_jumpers no)
		(fp_rect
			(start 0.4318 0.9525)
			(end -0.4318 -0.9525)
			(stroke
				(width 0)
				(type default)
			)
			(fill no)
			(layer "B.CrtYd")
		)
		(fp_rect
			(start 0.4318 0.9525)
			(end -0.4318 -0.9525)
			(stroke
				(width 0)
				(type default)
			)
			(fill no)
			(layer "B.Fab")
		)
		(pad "1" smd custom
			(at 0 -0.4445 90)
			(size 0.1524 0.1524)
			(layers "B.Cu" "B.Mask" "B.Paste")
			(net "VR_PVDDQ_DEF_AIREF2")
			(options
				(clearance outline)
				(anchor circle)
			)
			(primitives
				(gr_poly
					(pts
						(arc
							(start 0.3048 0.2032)
							(mid 0.275042 0.275042)
							(end 0.2032 0.3048)
						)
						(arc
							(start -0.2032 0.3048)
							(mid -0.275042 0.275042)
							(end -0.3048 0.2032)
						)
						(arc
							(start -0.3048 -0.2032)
							(mid -0.275042 -0.275042)
							(end -0.2032 -0.3048)
						)
						(arc
							(start 0.2032 -0.3048)
							(mid 0.275042 -0.275042)
							(end 0.3048 -0.2032)
						)
					)
					(width 0)
					(fill yes)
				)
			)
		)
		(pad "2" smd custom
			(at 0 0.4445 90)
			(size 0.1524 0.1524)
			(layers "B.Cu" "B.Mask" "B.Paste")
			(net "ISENSE_PVDDQ_DEF_PH2_IMON")
			(options
				(clearance outline)
				(anchor circle)
			)
			(primitives
				(gr_poly
					(pts
						(arc
							(start 0.3048 0.2032)
							(mid 0.275042 0.275042)
							(end 0.2032 0.3048)
						)
						(arc
							(start -0.2032 0.3048)
							(mid -0.275042 0.275042)
							(end -0.3048 0.2032)
						)
						(arc
							(start -0.3048 -0.2032)
							(mid -0.275042 -0.275042)
							(end -0.2032 -0.3048)
						)
						(arc
							(start 0.2032 -0.3048)
							(mid 0.275042 -0.275042)
							(end 0.3048 -0.2032)
						)
					)
					(width 0)
					(fill yes)
				)
			)
		)
	)
)
